(kicad_pcb
	(version 20241229)
	(generator "pcbnew")
	(generator_version "9.0")
	(general
		(thickness 1.711)
		(legacy_teardrops no)
	)
	(paper "A4")
	(title_block
		(title "Antmicro Baseboard for Jetson AGX Thor")
		(date "2026-02-18")
		(rev "1.1.0")
		(company "Antmicro Ltd")
		(comment 1 "www.antmicro.com")
		(comment 9 "footprints 566-570 of 1170")
	)
	(layers
		(0 "F.Cu" signal)
		(4 "In1.Cu" signal)
		(6 "In2.Cu" signal)
		(8 "In3.Cu" signal)
		(10 "In4.Cu" jumper)
		(12 "In5.Cu" signal)
		(14 "In6.Cu" signal)
		(16 "In7.Cu" signal)
		(18 "In8.Cu" signal)
		(2 "B.Cu" signal)
		(9 "F.Adhes" user "F.Adhesive")
		(11 "B.Adhes" user "B.Adhesive")
		(13 "F.Paste" user)
		(15 "B.Paste" user)
		(5 "F.SilkS" user "F.Silkscreen")
		(7 "B.SilkS" user "B.Silkscreen")
		(1 "F.Mask" user)
		(3 "B.Mask" user)
		(17 "Dwgs.User" user "User.Drawings")
		(19 "Cmts.User" user "User.Comments")
		(21 "Eco1.User" user "User.Eco1")
		(23 "Eco2.User" user "User.Eco2")
		(25 "Edge.Cuts" user)
		(27 "Margin" user)
		(31 "F.CrtYd" user "F.Courtyard")
		(29 "B.CrtYd" user "B.Courtyard")
		(35 "F.Fab" user)
		(33 "B.Fab" user)
	)
	(footprint "antmicro-footprints:QFN-2L_1.6x1x0.55mm"
		(layer "F.Cu")
		(at 159.9 74.1 90)
		(property "Reference" "D56"
			(at -0.7 -0.8 90)
			(layer "F.SilkS")
			(effects
				(font
					(size 0.7 0.7)
					(thickness 0.15)
				)
				(justify left bottom)
			)
		)
		(property "Value" "ESDA25P35-1U1M"
			(at 0 1.7 90)
			(layer "F.Fab")
			(effects
				(font
					(size 0.7 0.7)
					(thickness 0.15)
				)
				(justify left bottom)
			)
		)
		(property "Datasheet" "https://www.st.com/resource/en/datasheet/esda25p35-1u1m.pdf"
			(at 0 0 90)
			(layer "F.Fab")
			(hide yes)
			(effects
				(font
					(size 1.27 1.27)
					(thickness 0.15)
				)
			)
		)
		(property "Description" "Unidirectional TVS, 30 kV, QFN-2L, 22 V, 195 pF"
			(at 0 0 90)
			(layer "F.Fab")
			(hide yes)
			(effects
				(font
					(size 1.27 1.27)
					(thickness 0.15)
				)
			)
		)
		(property "Manufacturer" "STMicroelectronics"
			(at 0 0 90)
			(unlocked yes)
			(layer "F.Fab")
			(hide yes)
			(effects
				(font
					(size 1 1)
					(thickness 0.15)
				)
			)
		)
		(property "MPN" "ESDA25P35-1U1M"
			(at 0 0 90)
			(unlocked yes)
			(layer "F.Fab")
			(hide yes)
			(effects
				(font
					(size 1 1)
					(thickness 0.15)
				)
			)
		)
		(property "Author" "Antmicro"
			(at 0 0 90)
			(unlocked yes)
			(layer "F.Fab")
			(hide yes)
			(effects
				(font
					(size 1 1)
					(thickness 0.15)
				)
			)
		)
		(property "License" "Apache-2.0"
			(at 0 0 90)
			(unlocked yes)
			(layer "F.Fab")
			(hide yes)
			(effects
				(font
					(size 1 1)
					(thickness 0.15)
				)
			)
		)
		(component_classes
			(class "DCDC_20V")
		)
		(sheetname "/DCDC/")
		(sheetfile "dcdc.kicad_sch")
		(attr smd)
		(fp_line
			(start 0.23 -0.45)
			(end -0.23 -0.45)
			(stroke
				(width 0.15)
				(type solid)
			)
			(layer "F.SilkS")
		)
		(fp_line
			(start -1.2 -0.4)
			(end -1.2 0.4)
			(stroke
				(width 0.15)
				(type solid)
			)
			(layer "F.SilkS")
		)
		(fp_line
			(start 0.23 0.45)
			(end -0.23 0.45)
			(stroke
				(width 0.15)
				(type solid)
			)
			(layer "F.SilkS")
		)
		(fp_rect
			(start 1.25 0.65)
			(end -1.25 -0.65)
			(stroke
				(width 0.05)
				(type solid)
			)
			(fill no)
			(layer "F.CrtYd")
		)
		(fp_line
			(start 0.201 -0.202)
			(end -0.101 0)
			(stroke
				(width 0.15)
				(type solid)
			)
			(layer "F.Fab")
		)
		(fp_line
			(start -0.199 -0.202)
			(end -0.199 0.1)
			(stroke
				(width 0.15)
				(type solid)
			)
			(layer "F.Fab")
		)
		(fp_line
			(start 0.599 0)
			(end 0.201 0)
			(stroke
				(width 0.15)
				(type solid)
			)
			(layer "F.Fab")
		)
		(fp_line
			(start 0.201 0)
			(end 0.201 -0.202)
			(stroke
				(width 0.15)
				(type solid)
			)
			(layer "F.Fab")
		)
		(fp_line
			(start -0.101 0)
			(end 0.201 0.2)
			(stroke
				(width 0.15)
				(type solid)
			)
			(layer "F.Fab")
		)
		(fp_line
			(start -0.199 0)
			(end -0.597 0)
			(stroke
				(width 0.15)
				(type solid)
			)
			(layer "F.Fab")
		)
		(fp_line
			(start 0.201 0.2)
			(end 0.201 0)
			(stroke
				(width 0.15)
				(type solid)
			)
			(layer "F.Fab")
		)
		(fp_line
			(start -0.199 0.2)
			(end -0.199 0.1)
			(stroke
				(width 0.15)
				(type solid)
			)
			(layer "F.Fab")
		)
		(fp_rect
			(start 0.848 0.4)
			(end -0.85 -0.402)
			(stroke
				(width 0.15)
				(type solid)
			)
			(fill no)
			(layer "F.Fab")
		)
		(fp_text user "${REFERENCE}"
			(at -1.31 3.769 90)
			(layer "F.Fab")
			(effects
				(font
					(size 0.7 0.7)
					(thickness 0.15)
				)
				(justify left bottom)
			)
		)
		(fp_text user "Author: Antmicro"
			(at -1.31 4.769 90)
			(layer "F.Fab")
			(effects
				(font
					(size 0.7 0.7)
					(thickness 0.15)
				)
				(justify left bottom)
			)
		)
		(fp_text user "License: Apache-2.0"
			(at -1.31 5.769 90)
			(layer "F.Fab")
			(effects
				(font
					(size 0.7 0.7)
					(thickness 0.15)
				)
				(justify left bottom)
			)
		)
		(pad "1" smd roundrect
			(at -0.7 0 270)
			(size 0.8 1)
			(layers "F.Cu" "F.Mask" "F.Paste")
			(roundrect_rratio 0.2)
			(net 904 "+20V")
			(pinfunction "C")
			(pintype "passive")
		)
		(pad "2" smd roundrect
			(at 0.7 0 270)
			(size 0.8 1)
			(layers "F.Cu" "F.Mask" "F.Paste")
			(roundrect_rratio 0.2)
			(net 1 "GND")
			(pinfunction "A")
			(pintype "passive")
		)
	)
	(footprint "antmicro-footprints:R_0402_1005Metric"
		(layer "F.Cu")
		(at 203.6 135.7 180)
		(descr "Resistor SMD 0402")
		(tags "resistor SMD 0402")
		(property "Reference" "R82"
			(at 2.8 0.4 0)
			(layer "F.SilkS")
			(effects
				(font
					(size 0.7 0.7)
					(thickness 0.15)
				)
				(justify right top)
			)
		)
		(property "Value" "R_49k9_0402"
			(at -1.011843 1.772046 0)
			(layer "F.Fab")
			(effects
				(font
					(size 0.7 0.7)
					(thickness 0.15)
				)
				(justify right top)
			)
		)
		(property "Datasheet" "https://www.bourns.com/docs/product-datasheets/cr.pdf"
			(at 0 0 0)
			(layer "F.Fab")
			(hide yes)
			(effects
				(font
					(size 1.27 1.27)
					(thickness 0.15)
				)
			)
		)
		(property "Description" "SMD Chip Resistor, 49.9 kohm, ± 1%, 63 mW, 0402 [1005 Metric], Thick Film, General Purpose"
			(at 0 0 0)
			(layer "F.Fab")
			(hide yes)
			(effects
				(font
					(size 1.27 1.27)
					(thickness 0.15)
				)
			)
		)
		(property "MPN" "CR0402-FX-4992GLF"
			(at 0 0 180)
			(unlocked yes)
			(layer "F.Fab")
			(hide yes)
			(effects
				(font
					(size 1 1)
					(thickness 0.15)
				)
			)
		)
		(property "Manufacturer" "Bourns"
			(at 0 0 180)
			(unlocked yes)
			(layer "F.Fab")
			(hide yes)
			(effects
				(font
					(size 1 1)
					(thickness 0.15)
				)
			)
		)
		(property "License" "Apache-2.0"
			(at 0 0 180)
			(unlocked yes)
			(layer "F.Fab")
			(hide yes)
			(effects
				(font
					(size 1 1)
					(thickness 0.15)
				)
			)
		)
		(property "Author" "Antmicro"
			(at 0 0 180)
			(unlocked yes)
			(layer "F.Fab")
			(hide yes)
			(effects
				(font
					(size 1 1)
					(thickness 0.15)
				)
			)
		)
		(property "Val" "49k9"
			(at 0 0 180)
			(unlocked yes)
			(layer "F.Fab")
			(hide yes)
			(effects
				(font
					(size 1 1)
					(thickness 0.15)
				)
			)
		)
		(property "Tolerance" "1%"
			(at 0 0 180)
			(unlocked yes)
			(layer "F.Fab")
			(hide yes)
			(effects
				(font
					(size 1 1)
					(thickness 0.15)
				)
			)
		)
		(sheetname "/USB Hub/")
		(sheetfile "usb_hub.kicad_sch")
		(attr smd)
		(fp_poly
			(pts
				(xy -0.925 -0.47) (xy -0.925 0.47) (xy 0.925 0.47) (xy 0.925 -0.47)
			)
			(stroke
				(width 0.05)
				(type default)
			)
			(fill no)
			(layer "F.CrtYd")
		)
		(fp_poly
			(pts
				(xy -0.5 -0.25) (xy -0.5 0.25) (xy 0.5 0.25) (xy 0.5 -0.25)
			)
			(stroke
				(width 0.15)
				(type solid)
			)
			(fill no)
			(layer "F.Fab")
		)
		(fp_text user "Author: Antmicro"
			(at -0.95 4.169 0)
			(layer "F.Fab")
			(effects
				(font
					(size 0.7 0.7)
					(thickness 0.15)
				)
				(justify right top)
			)
		)
		(fp_text user "${REFERENCE}"
			(at -0.95 3.168 0)
			(layer "F.Fab")
			(effects
				(font
					(size 0.7 0.7)
					(thickness 0.15)
				)
				(justify right top)
			)
		)
		(fp_text user "License: Apache-2.0"
			(at -0.949999 5.169 0)
			(layer "F.Fab")
			(effects
				(font
					(size 0.7 0.7)
					(thickness 0.15)
				)
				(justify right top)
			)
		)
		(pad "1" smd roundrect
			(at -0.48 0 180)
			(size 0.59 0.64)
			(layers "F.Cu" "F.Mask" "F.Paste")
			(roundrect_rratio 0.25)
			(net 1 "GND")
			(pintype "passive")
		)
		(pad "2" smd roundrect
			(at 0.48 0 180)
			(size 0.59 0.64)
			(layers "F.Cu" "F.Mask" "F.Paste")
			(roundrect_rratio 0.25)
			(net 1164 "/USB Hub/VBUS_MON_UP")
			(pintype "passive")
		)
	)
	(footprint "antmicro-footprints:SW_KMR211NGLFS_SMD"
		(layer "F.Cu")
		(at 199 55.52)
		(property "Reference" "S1"
			(at -3.2 2.78 180)
			(layer "F.SilkS")
			(hide yes)
			(effects
				(font
					(size 0.7 0.7)
					(thickness 0.15)
				)
				(justify left bottom)
			)
		)
		(property "Value" "SW_KMR211NGLFS_SMD"
			(at 0 2.8 0)
			(layer "F.Fab")
			(effects
				(font
					(size 0.7 0.7)
					(thickness 0.15)
				)
				(justify left bottom)
			)
		)
		(property "Datasheet" "http://www.farnell.com/datasheets/2631211.pdf"
			(at 0 0 0)
			(layer "F.Fab")
			(hide yes)
			(effects
				(font
					(size 1.27 1.27)
					(thickness 0.15)
				)
			)
		)
		(property "Description" "Tactile Switch, KMR 2 Series, Top Actuated, Surface Mount, Oval Button, 120 gf, 50mA at 32VDC"
			(at 0 0 0)
			(layer "F.Fab")
			(hide yes)
			(effects
				(font
					(size 1.27 1.27)
					(thickness 0.15)
				)
			)
		)
		(property "MPN" "KMR211NGLFS"
			(at 0 0 0)
			(unlocked yes)
			(layer "F.Fab")
			(hide yes)
			(effects
				(font
					(size 1 1)
					(thickness 0.15)
				)
			)
		)
		(property "Manufacturer" "C&K"
			(at 0 0 0)
			(unlocked yes)
			(layer "F.Fab")
			(hide yes)
			(effects
				(font
					(size 1 1)
					(thickness 0.15)
				)
			)
		)
		(property "Author" "Antmicro"
			(at 0 0 0)
			(unlocked yes)
			(layer "F.Fab")
			(hide yes)
			(effects
				(font
					(size 1 1)
					(thickness 0.15)
				)
			)
		)
		(property "License" "Apache-2.0"
			(at 0 0 0)
			(unlocked yes)
			(layer "F.Fab")
			(hide yes)
			(effects
				(font
					(size 1 1)
					(thickness 0.15)
				)
			)
		)
		(sheetname "/SoM_Power/")
		(sheetfile "som_power.kicad_sch")
		(attr smd)
		(fp_line
			(start -2.1 -1.6)
			(end -2.1 -1.499)
			(stroke
				(width 0.15)
				(type solid)
			)
			(layer "F.SilkS")
		)
		(fp_line
			(start -2.1 1.601)
			(end -2.1 1.48)
			(stroke
				(width 0.15)
				(type solid)
			)
			(layer "F.SilkS")
		)
		(fp_line
			(start 2.101 -1.6)
			(end -2.1 -1.6)
			(stroke
				(width 0.15)
				(type solid)
			)
			(layer "F.SilkS")
		)
		(fp_line
			(start 2.101 -1.58)
			(end 2.101 -1.459)
			(stroke
				(width 0.15)
				(type solid)
			)
			(layer "F.SilkS")
		)
		(fp_line
			(start 2.101 1.601)
			(end -2.1 1.601)
			(stroke
				(width 0.15)
				(type solid)
			)
			(layer "F.SilkS")
		)
		(fp_line
			(start 2.101 1.601)
			(end 2.101 1.48)
			(stroke
				(width 0.15)
				(type solid)
			)
			(layer "F.SilkS")
		)
		(fp_poly
			(pts
				(xy 2.751 1.75) (xy 2.751 -1.749) (xy -2.748 -1.749) (xy -2.748 1.749999)
			)
			(stroke
				(width 0.05)
				(type solid)
			)
			(fill no)
			(layer "F.CrtYd")
		)
		(fp_line
			(start -2.1 -1.6)
			(end -2.1 1.601)
			(stroke
				(width 0.15)
				(type solid)
			)
			(layer "F.Fab")
		)
		(fp_line
			(start -2.1 1.601)
			(end 2.101 1.601)
			(stroke
				(width 0.15)
				(type solid)
			)
			(layer "F.Fab")
		)
		(fp_line
			(start -0.248 -0.8)
			(end 0.25 -0.8)
			(stroke
				(width 0.15)
				(type solid)
			)
			(layer "F.Fab")
		)
		(fp_line
			(start 0.25 0.802)
			(end -0.248 0.802)
			(stroke
				(width 0.15)
				(type solid)
			)
			(layer "F.Fab")
		)
		(fp_line
			(start 2.101 -1.6)
			(end -2.1 -1.6)
			(stroke
				(width 0.15)
				(type solid)
			)
			(layer "F.Fab")
		)
		(fp_line
			(start 2.101 1.601)
			(end 2.101 -1.6)
			(stroke
				(width 0.15)
				(type solid)
			)
			(layer "F.Fab")
		)
		(fp_arc
			(start -0.248 0.802)
			(mid -1.050001 0.001)
			(end -0.248 -0.8)
			(stroke
				(width 0.15)
				(type solid)
			)
			(layer "F.Fab")
		)
		(fp_arc
			(start 0.25 -0.8)
			(mid 1.051001 0.001)
			(end 0.25 0.802)
			(stroke
				(width 0.15)
				(type solid)
			)
			(layer "F.Fab")
		)
		(fp_text user "Author: Antmicro"
			(at -3 5.5 0)
			(layer "F.Fab")
			(effects
				(font
					(size 0.7 0.7)
					(thickness 0.15)
				)
				(justify left bottom)
			)
		)
		(fp_text user "License: Apache-2.0"
			(at -3 6.75 0)
			(layer "F.Fab")
			(effects
				(font
					(size 0.7 0.7)
					(thickness 0.15)
				)
				(justify left bottom)
			)
		)
		(fp_text user "${REFERENCE}"
			(at -3 4.25 0)
			(layer "F.Fab")
			(effects
				(font
					(size 0.7 0.7)
					(thickness 0.15)
				)
				(justify left bottom)
			)
		)
		(pad "1" smd rect
			(at -2.048 -0.8 180)
			(size 0.9 1)
			(layers "F.Cu" "F.Mask" "F.Paste")
			(net 1 "GND")
			(pinfunction "1")
			(pintype "passive")
		)
		(pad "2" smd rect
			(at 2.049999 -0.8 180)
			(size 0.9 1)
			(layers "F.Cu" "F.Mask" "F.Paste")
			(net 1 "GND")
			(pinfunction "2")
			(pintype "passive")
		)
		(pad "3" smd rect
			(at -2.048 0.802 180)
			(size 0.9 1)
			(layers "F.Cu" "F.Mask" "F.Paste")
			(net 702 "/SoM_Power/~{SYS_RESET}")
			(pinfunction "3")
			(pintype "passive")
		)
		(pad "4" smd rect
			(at 2.05 0.802001 180)
			(size 0.9 1)
			(layers "F.Cu" "F.Mask" "F.Paste")
			(net 702 "/SoM_Power/~{SYS_RESET}")
			(pinfunction "4")
			(pintype "passive")
		)
	)
	(footprint "antmicro-footprints:TP_SMD_0.75mm"
		(layer "F.Cu")
		(at 67.51 58.29 90)
		(property "Reference" "TP26"
			(at 1.59 -2.86 90)
			(layer "F.SilkS")
			(effects
				(font
					(size 0.7 0.7)
					(thickness 0.15)
				)
				(justify left bottom)
			)
		)
		(property "Value" "TP_0.75mm_SMD"
			(at 0 1.2 90)
			(layer "F.Fab")
			(effects
				(font
					(size 0.7 0.7)
					(thickness 0.15)
				)
				(justify left bottom)
			)
		)
		(property "Description" "SMT test point"
			(at 0 0 90)
			(layer "F.Fab")
			(hide yes)
			(effects
				(font
					(size 1.27 1.27)
					(thickness 0.15)
				)
			)
		)
		(property "MPN" ""
			(at 0 0 90)
			(unlocked yes)
			(layer "F.Fab")
			(hide yes)
			(effects
				(font
					(size 1 1)
					(thickness 0.15)
				)
			)
		)
		(property "Manufacturer" ""
			(at 0 0 90)
			(unlocked yes)
			(layer "F.Fab")
			(hide yes)
			(effects
				(font
					(size 1 1)
					(thickness 0.15)
				)
			)
		)
		(property "Author" "Antmicro"
			(at 0 0 90)
			(unlocked yes)
			(layer "F.Fab")
			(hide yes)
			(effects
				(font
					(size 1 1)
					(thickness 0.15)
				)
			)
		)
		(property "License" "Apache-2.0"
			(at 0 0 90)
			(unlocked yes)
			(layer "F.Fab")
			(hide yes)
			(effects
				(font
					(size 1 1)
					(thickness 0.15)
				)
			)
		)
		(sheetname "/CSI/")
		(sheetfile "csi.kicad_sch")
		(attr exclude_from_pos_files exclude_from_bom)
		(fp_circle
			(center 0 0)
			(end 0.475 0)
			(stroke
				(width 0.05)
				(type default)
			)
			(fill no)
			(layer "F.CrtYd")
		)
		(fp_text user "License: Apache-2.0"
			(at -0.4 5.101 90)
			(layer "F.Fab")
			(effects
				(font
					(size 0.7 0.7)
					(thickness 0.15)
				)
				(justify left bottom)
			)
		)
		(fp_text user "Author: Antmicro"
			(at -0.4 3.901 90)
			(layer "F.Fab")
			(effects
				(font
					(size 0.7 0.7)
					(thickness 0.15)
				)
				(justify left bottom)
			)
		)
		(fp_text user "${REFERENCE}"
			(at -0.4 2.7 90)
			(layer "F.Fab")
			(effects
				(font
					(size 0.7 0.7)
					(thickness 0.15)
				)
				(justify left bottom)
			)
		)
		(pad "1" smd circle
			(at 0 0 90)
			(size 0.75 0.75)
			(layers "F.Cu" "F.Mask")
			(net 1050 "/CSI/MUX_I2C_6_SCL")
			(pinfunction "1")
			(pintype "passive")
		)
	)
	(footprint "antmicro-footprints:R_0402_1005Metric"
		(layer "F.Cu")
		(at 190.6 81.4)
		(descr "Resistor SMD 0402")
		(tags "resistor SMD 0402")
		(property "Reference" "R105"
			(at -3.8 0.5 0)
			(layer "F.SilkS")
			(effects
				(font
					(size 0.7 0.7)
					(thickness 0.15)
				)
				(justify left bottom)
			)
		)
		(property "Value" "R_4k7_0402"
			(at -1.011843 1.772046 0)
			(layer "F.Fab")
			(effects
				(font
					(size 0.7 0.7)
					(thickness 0.15)
				)
				(justify left bottom)
			)
		)
		(property "Datasheet" "https://www.bourns.com/docs/product-datasheets/cr.pdf"
			(at 0 0 0)
			(layer "F.Fab")
			(hide yes)
			(effects
				(font
					(size 1.27 1.27)
					(thickness 0.15)
				)
			)
		)
		(property "Description" "SMD Chip Resistor, 4.7 kohm, ± 1%, 62.5 mW, 0402 [1005 Metric], Thick Film, General Purpose"
			(at 0 0 0)
			(layer "F.Fab")
			(hide yes)
			(effects
				(font
					(size 1.27 1.27)
					(thickness 0.15)
				)
			)
		)
		(property "Manufacturer" "Bourns"
			(at 0 0 0)
			(unlocked yes)
			(layer "F.Fab")
			(hide yes)
			(effects
				(font
					(size 1 1)
					(thickness 0.15)
				)
			)
		)
		(property "MPN" "CR0402-FX-4701GLF"
			(at 0 0 0)
			(unlocked yes)
			(layer "F.Fab")
			(hide yes)
			(effects
				(font
					(size 1 1)
					(thickness 0.15)
				)
			)
		)
		(property "Val" "4k7"
			(at 0 0 0)
			(unlocked yes)
			(layer "F.Fab")
			(hide yes)
			(effects
				(font
					(size 1 1)
					(thickness 0.15)
				)
			)
		)
		(property "License" "Apache-2.0"
			(at 0 0 0)
			(unlocked yes)
			(layer "F.Fab")
			(hide yes)
			(effects
				(font
					(size 1 1)
					(thickness 0.15)
				)
			)
		)
		(property "Author" "Antmicro"
			(at 0 0 0)
			(unlocked yes)
			(layer "F.Fab")
			(hide yes)
			(effects
				(font
					(size 1 1)
					(thickness 0.15)
				)
			)
		)
		(property "Tolerance" "1%"
			(at 0 0 0)
			(unlocked yes)
			(layer "F.Fab")
			(hide yes)
			(effects
				(font
					(size 1 1)
					(thickness 0.15)
				)
			)
		)
		(sheetname "/USB Debug, PD/")
		(sheetfile "usb_debug_pd.kicad_sch")
		(attr smd)
		(fp_poly
			(pts
				(xy -0.925 -0.47) (xy -0.925 0.47) (xy 0.925 0.47) (xy 0.925 -0.47)
			)
			(stroke
				(width 0.05)
				(type default)
			)
			(fill no)
			(layer "F.CrtYd")
		)
		(fp_poly
			(pts
				(xy -0.5 -0.25) (xy -0.5 0.25) (xy 0.5 0.25) (xy 0.5 -0.25)
			)
			(stroke
				(width 0.15)
				(type solid)
			)
			(fill no)
			(layer "F.Fab")
		)
		(fp_text user "License: Apache-2.0"
			(at -0.949999 5.169 0)
			(layer "F.Fab")
			(effects
				(font
					(size 0.7 0.7)
					(thickness 0.15)
				)
				(justify left bottom)
			)
		)
		(fp_text user "Author: Antmicro"
			(at -0.95 4.169 0)
			(layer "F.Fab")
			(effects
				(font
					(size 0.7 0.7)
					(thickness 0.15)
				)
				(justify left bottom)
			)
		)
		(fp_text user "${REFERENCE}"
			(at -0.95 3.168 0)
			(layer "F.Fab")
			(effects
				(font
					(size 0.7 0.7)
					(thickness 0.15)
				)
				(justify left bottom)
			)
		)
		(pad "1" smd roundrect
			(at -0.48 0)
			(size 0.59 0.64)
			(layers "F.Cu" "F.Mask" "F.Paste")
			(roundrect_rratio 0.25)
			(net 2 "+3V3")
			(pintype "passive")
		)
		(pad "2" smd roundrect
			(at 0.48 0)
			(size 0.59 0.64)
			(layers "F.Cu" "F.Mask" "F.Paste")
			(roundrect_rratio 0.25)
			(net 947 "/USB Debug, PD/PDC_I2C2_SCL")
			(pintype "passive")
		)
	)
)
